(kicad_pcb
	(version 20260206)
	(generator "pcbnew")
	(generator_version "10.0")
	(general
		(thickness 1.6)
		(legacy_teardrops no)
	)
	(paper "A4")
	(title_block
		(title "Wiwynn_Tioga_Pass_MB.brd")
		(comment 1 "Tioga Pass / footprints 1447-1451 of 4770")
	)
	(layers
		(0 "F.Cu" signal "TOP")
		(4 "In1.Cu" signal "L2GND")
		(6 "In2.Cu" signal "L3")
		(8 "In3.Cu" signal "L4GND")
		(10 "In4.Cu" signal "L5")
		(12 "In5.Cu" signal "L6GND")
		(14 "In6.Cu" signal "L7VCC")
		(16 "In7.Cu" signal "L8VCC")
		(18 "In8.Cu" signal "L9GND")
		(20 "In9.Cu" signal "L10")
		(22 "In10.Cu" signal "L11GND")
		(24 "In11.Cu" signal "L12")
		(26 "In12.Cu" signal "L13GND")
		(2 "B.Cu" signal "BOTTOM")
		(9 "F.Adhes" user "F.Adhesive")
		(11 "B.Adhes" user "B.Adhesive")
		(13 "F.Paste" user "Package Geometry/Pastemask Top")
		(15 "B.Paste" user "Package Geometry/Pastemask Bottom")
		(5 "F.SilkS" user "Ref Des/Silkscreen Top")
		(7 "B.SilkS" user "Ref Des/Silkscreen Bottom")
		(1 "F.Mask" user "Board Geometry/Soldermask Top")
		(3 "B.Mask" user "Board Geometry/Soldermask Bottom")
		(17 "Dwgs.User" user "User.Drawings")
		(19 "Cmts.User" user "User.Comments")
		(21 "Eco1.User" user "User.Eco1")
		(23 "Eco2.User" user "User.Eco2")
		(25 "Edge.Cuts" user "Board Geometry/Outline")
		(27 "Margin" user)
		(31 "F.CrtYd" user "Package Geometry/Place Bound Top")
		(29 "B.CrtYd" user "Package Geometry/Place Bound Bottom")
		(35 "F.Fab" user "Ref Des/Assembly Top")
		(33 "B.Fab" user "Ref Des/Assembly Bottom")
	)
	(footprint ""
		(layer "F.Cu")
		(at 85.777578 -75.65009 180)
		(property "Reference" "XLU2"
			(at 22.150578 34.43224 0)
			(unlocked yes)
			(layer "F.SilkS")
			(effects
				(font
					(size 0.7874 0.5842)
					(thickness 0.1524)
				)
				(justify left)
			)
		)
		(property "Value" ""
			(at 0 0 180)
			(layer "F.Fab")
			(effects
				(font
					(size 1.27 1.27)
				)
			)
		)
		(duplicate_pad_numbers_are_jumpers no)
		(fp_line
			(start 21.77796 31.949898)
			(end 21.77796 8.899906)
			(stroke
				(width 0.1524)
				(type default)
			)
			(layer "F.SilkS")
		)
		(fp_line
			(start 21.77796 8.899906)
			(end 18.278094 5.40004)
			(stroke
				(width 0.1524)
				(type default)
			)
			(layer "F.SilkS")
		)
		(fp_line
			(start 21.77796 -7.100062)
			(end 21.77796 -30.150054)
			(stroke
				(width 0.1524)
				(type default)
			)
			(layer "F.SilkS")
		)
		(fp_line
			(start 21.77796 -30.150054)
			(end 14.777974 -30.150054)
			(stroke
				(width 0.1524)
				(type default)
			)
			(layer "F.SilkS")
		)
		(fp_line
			(start 18.278094 5.40004)
			(end 18.278094 3.899916)
			(stroke
				(width 0.1524)
				(type default)
			)
			(layer "F.SilkS")
		)
		(fp_line
			(start 18.278094 3.899916)
			(end 17.777968 3.899916)
			(stroke
				(width 0.1524)
				(type default)
			)
			(layer "F.SilkS")
		)
		(fp_line
			(start 18.278094 -2.100072)
			(end 18.278094 -3.599942)
			(stroke
				(width 0.1524)
				(type default)
			)
			(layer "F.SilkS")
		)
		(fp_line
			(start 18.278094 -3.599942)
			(end 21.77796 -7.100062)
			(stroke
				(width 0.1524)
				(type default)
			)
			(layer "F.SilkS")
		)
		(fp_line
			(start 17.777968 3.899916)
			(end 17.777968 -2.100072)
			(stroke
				(width 0.1524)
				(type default)
			)
			(layer "F.SilkS")
		)
		(fp_line
			(start 17.777968 -2.100072)
			(end 18.278094 -2.100072)
			(stroke
				(width 0.1524)
				(type default)
			)
			(layer "F.SilkS")
		)
		(fp_line
			(start 14.777974 31.949898)
			(end 21.77796 31.949898)
			(stroke
				(width 0.1524)
				(type default)
			)
			(layer "F.SilkS")
		)
		(fp_line
			(start 14.777974 29.399992)
			(end 14.777974 31.949898)
			(stroke
				(width 0.1524)
				(type default)
			)
			(layer "F.SilkS")
		)
		(fp_line
			(start 14.777974 -27.599894)
			(end -17.622012 -27.599894)
			(stroke
				(width 0.1524)
				(type default)
			)
			(layer "F.SilkS")
		)
		(fp_line
			(start 14.777974 -30.150054)
			(end 14.777974 -27.599894)
			(stroke
				(width 0.1524)
				(type default)
			)
			(layer "F.SilkS")
		)
		(fp_line
			(start -6.171946 6.690106)
			(end -12.761976 10.649966)
			(stroke
				(width 0.1524)
				(type default)
			)
			(layer "F.SilkS")
		)
		(fp_line
			(start -6.171946 -4.890008)
			(end -6.171946 6.690106)
			(stroke
				(width 0.1524)
				(type default)
			)
			(layer "F.SilkS")
		)
		(fp_line
			(start -12.761976 10.649966)
			(end -19.221958 10.649966)
			(stroke
				(width 0.1524)
				(type default)
			)
			(layer "F.SilkS")
		)
		(fp_line
			(start -12.761976 -8.850122)
			(end -6.171946 -4.890008)
			(stroke
				(width 0.1524)
				(type default)
			)
			(layer "F.SilkS")
		)
		(fp_line
			(start -17.622012 30.39999)
			(end -17.622012 29.399992)
			(stroke
				(width 0.1524)
				(type default)
			)
			(layer "F.SilkS")
		)
		(fp_line
			(start -17.622012 29.399992)
			(end 14.777974 29.399992)
			(stroke
				(width 0.1524)
				(type default)
			)
			(layer "F.SilkS")
		)
		(fp_line
			(start -17.622012 -27.599894)
			(end -17.622012 -28.599892)
			(stroke
				(width 0.1524)
				(type default)
			)
			(layer "F.SilkS")
		)
		(fp_line
			(start -17.622012 -28.599892)
			(end -18.62201 -28.599892)
			(stroke
				(width 0.1524)
				(type default)
			)
			(layer "F.SilkS")
		)
		(fp_line
			(start -18.62201 30.39999)
			(end -17.622012 30.39999)
			(stroke
				(width 0.1524)
				(type default)
			)
			(layer "F.SilkS")
		)
		(fp_line
			(start -18.62201 29.399992)
			(end -18.62201 30.39999)
			(stroke
				(width 0.1524)
				(type default)
			)
			(layer "F.SilkS")
		)
		(fp_line
			(start -18.62201 -8.850122)
			(end -12.761976 -8.850122)
			(stroke
				(width 0.1524)
				(type default)
			)
			(layer "F.SilkS")
		)
		(fp_line
			(start -18.62201 -28.599892)
			(end -18.62201 -8.850122)
			(stroke
				(width 0.1524)
				(type default)
			)
			(layer "F.SilkS")
		)
		(fp_line
			(start -19.221958 29.399992)
			(end -18.62201 29.399992)
			(stroke
				(width 0.1524)
				(type default)
			)
			(layer "F.SilkS")
		)
		(fp_line
			(start -19.221958 10.649966)
			(end -19.221958 29.399992)
			(stroke
				(width 0.1524)
				(type default)
			)
			(layer "F.SilkS")
		)
		(fp_poly
			(pts
				(xy 19.777964 -5.100066) (xy 19.777964 -22.649942) (xy 18.839434 -22.649942) (xy 18.839434 -27.410918)
				(xy 14.777974 -27.410918) (xy 14.777974 -30.150054) (xy 21.77796 -30.150054) (xy 21.77796 -7.100062)
			)
			(stroke
				(width 0)
				(type default)
			)
			(fill no)
			(layer "F.CrtYd")
		)
		(fp_poly
			(pts
				(arc
					(start 19.777964 17.616678)
					(mid 20.051978 16.900049)
					(end 19.777964 16.183356)
				)
				(xy 19.777964 6.89991) (xy 21.77796 8.899906) (xy 21.77796 31.949898) (xy 14.777974 31.949898) (xy 14.777974 29.211016)
				(xy 18.839434 29.211016) (xy 18.839434 24.449786) (xy 19.777964 24.449786)
			)
			(stroke
				(width 0)
				(type default)
			)
			(fill no)
			(layer "F.CrtYd")
		)
		(fp_line
			(start 21.77796 31.949898)
			(end 14.777974 31.949898)
			(stroke
				(width 0.1)
				(type default)
			)
			(layer "F.Fab")
		)
		(fp_line
			(start 21.77796 8.899906)
			(end 21.77796 31.949898)
			(stroke
				(width 0.1)
				(type default)
			)
			(layer "F.Fab")
		)
		(fp_line
			(start 21.77796 -7.100062)
			(end 19.777964 -5.100066)
			(stroke
				(width 0.1)
				(type default)
			)
			(layer "F.Fab")
		)
		(fp_line
			(start 21.77796 -30.150054)
			(end 21.77796 -7.100062)
			(stroke
				(width 0.1)
				(type default)
			)
			(layer "F.Fab")
		)
		(fp_line
			(start 19.777964 24.449786)
			(end 19.777964 22.078696)
			(stroke
				(width 0.1)
				(type default)
			)
			(layer "F.Fab")
		)
		(fp_line
			(start 19.777964 21.179028)
			(end 19.777964 17.616678)
			(stroke
				(width 0.1)
				(type default)
			)
			(layer "F.Fab")
		)
		(fp_line
			(start 19.777964 16.183356)
			(end 19.777964 6.89991)
			(stroke
				(width 0.1)
				(type default)
			)
			(layer "F.Fab")
		)
		(fp_line
			(start 19.777964 6.89991)
			(end 21.77796 8.899906)
			(stroke
				(width 0.1)
				(type default)
			)
			(layer "F.Fab")
		)
		(fp_line
			(start 19.777964 -5.100066)
			(end 19.777964 -22.649942)
			(stroke
				(width 0.1)
				(type default)
			)
			(layer "F.Fab")
		)
		(fp_line
			(start 19.777964 -22.649942)
			(end 18.839434 -22.649942)
			(stroke
				(width 0.1)
				(type default)
			)
			(layer "F.Fab")
		)
		(fp_line
			(start 18.839434 29.211016)
			(end 18.839434 24.449786)
			(stroke
				(width 0.1)
				(type default)
			)
			(layer "F.Fab")
		)
		(fp_line
			(start 18.839434 24.449786)
			(end 19.777964 24.449786)
			(stroke
				(width 0.1)
				(type default)
			)
			(layer "F.Fab")
		)
		(fp_line
			(start 18.839434 -22.649942)
			(end 18.839434 -27.410918)
			(stroke
				(width 0.1)
				(type default)
			)
			(layer "F.Fab")
		)
		(fp_line
			(start 18.839434 -27.410918)
			(end 14.777974 -27.410918)
			(stroke
				(width 0.1)
				(type default)
			)
			(layer "F.Fab")
		)
		(fp_line
			(start 14.777974 31.949898)
			(end 14.777974 29.211016)
			(stroke
				(width 0.1)
				(type default)
			)
			(layer "F.Fab")
		)
		(fp_line
			(start 14.777974 29.211016)
			(end 18.839434 29.211016)
			(stroke
				(width 0.1)
				(type default)
			)
			(layer "F.Fab")
		)
		(fp_line
			(start 14.777974 -27.410918)
			(end 14.777974 -30.150054)
			(stroke
				(width 0.1)
				(type default)
			)
			(layer "F.Fab")
		)
		(fp_line
			(start 14.777974 -30.150054)
			(end 21.77796 -30.150054)
			(stroke
				(width 0.1)
				(type default)
			)
			(layer "F.Fab")
		)
		(fp_arc
			(start 19.777964 22.078696)
			(mid 19.777668 21.628862)
			(end 19.777964 21.179028)
			(stroke
				(width 0.1)
				(type default)
			)
			(layer "F.Fab")
		)
		(fp_arc
			(start 19.777964 16.183356)
			(mid 20.051971 16.900015)
			(end 19.777964 17.616678)
			(stroke
				(width 0.1)
				(type default)
			)
			(layer "F.Fab")
		)
	)
	(footprint ""
		(layer "F.Cu")
		(at 21.80971 -119.62765 -90)
		(property "Reference" "CR1B2"
			(at 2.58699 1.60528 0)
			(unlocked yes)
			(layer "F.SilkS")
			(effects
				(font
					(size 0.7874 0.5842)
					(thickness 0.1524)
				)
				(justify left)
			)
		)
		(property "Value" ""
			(at 0 0 270)
			(layer "F.Fab")
			(effects
				(font
					(size 1.27 1.27)
				)
			)
		)
		(duplicate_pad_numbers_are_jumpers no)
		(fp_line
			(start -0.931418 2.543048)
			(end -0.931418 1.631442)
			(stroke
				(width 0.1524)
				(type default)
			)
			(layer "F.SilkS")
		)
		(fp_line
			(start -1.41224 1.631442)
			(end -0.931418 0.798576)
			(stroke
				(width 0.1524)
				(type default)
			)
			(layer "F.SilkS")
		)
		(fp_line
			(start -0.931418 1.631442)
			(end -1.41224 1.631442)
			(stroke
				(width 0.1524)
				(type default)
			)
			(layer "F.SilkS")
		)
		(fp_line
			(start -0.450596 1.631442)
			(end -0.931418 1.631442)
			(stroke
				(width 0.1524)
				(type default)
			)
			(layer "F.SilkS")
		)
		(fp_line
			(start -0.931418 0.798576)
			(end -0.450596 1.631442)
			(stroke
				(width 0.1524)
				(type default)
			)
			(layer "F.SilkS")
		)
		(fp_line
			(start -0.450596 0.798576)
			(end -1.41224 0.798576)
			(stroke
				(width 0.1524)
				(type default)
			)
			(layer "F.SilkS")
		)
		(fp_line
			(start -0.931418 -0.324866)
			(end -0.931418 0.798576)
			(stroke
				(width 0.1524)
				(type default)
			)
			(layer "F.SilkS")
		)
		(fp_rect
			(start 0.67437 2.04216)
			(end -0.67437 0.24384)
			(stroke
				(width 0)
				(type default)
			)
			(fill no)
			(layer "F.CrtYd")
		)
		(fp_line
			(start -0.67437 2.04216)
			(end 0.67437 2.04216)
			(stroke
				(width 0.1)
				(type default)
			)
			(layer "F.Fab")
		)
		(fp_line
			(start 0.67437 2.04216)
			(end 0.67437 0.24384)
			(stroke
				(width 0.1)
				(type default)
			)
			(layer "F.Fab")
		)
		(fp_line
			(start -1.412748 1.621536)
			(end -0.931926 0.78867)
			(stroke
				(width 0.1)
				(type default)
			)
			(layer "F.Fab")
		)
		(fp_line
			(start -0.931926 1.621536)
			(end -0.931926 2.533142)
			(stroke
				(width 0.1)
				(type default)
			)
			(layer "F.Fab")
		)
		(fp_line
			(start -0.451104 1.621536)
			(end -1.412748 1.621536)
			(stroke
				(width 0.1)
				(type default)
			)
			(layer "F.Fab")
		)
		(fp_line
			(start -0.931926 0.78867)
			(end -0.451104 1.621536)
			(stroke
				(width 0.1)
				(type default)
			)
			(layer "F.Fab")
		)
		(fp_line
			(start -0.931926 0.78867)
			(end -0.931926 -0.334772)
			(stroke
				(width 0.1)
				(type default)
			)
			(layer "F.Fab")
		)
		(fp_line
			(start -0.451104 0.78867)
			(end -1.412748 0.78867)
			(stroke
				(width 0.1)
				(type default)
			)
			(layer "F.Fab")
		)
		(fp_line
			(start -0.67437 0.24384)
			(end -0.67437 2.04216)
			(stroke
				(width 0.1)
				(type default)
			)
			(layer "F.Fab")
		)
		(fp_line
			(start 0.67437 0.24384)
			(end -0.67437 0.24384)
			(stroke
				(width 0.1)
				(type default)
			)
			(layer "F.Fab")
		)
		(pad "1" smd rect
			(at 0 0 270)
			(size 0.4064 1.016)
			(layers "F.Cu" "F.Mask" "F.Paste")
			(net "FAN_TACH2_CPU1_D1")
		)
		(pad "2" smd rect
			(at 0 2.286 270)
			(size 0.4064 1.016)
			(layers "F.Cu" "F.Mask" "F.Paste")
			(net "FAN_TACH2_CPU1_D2")
		)
	)
	(footprint ""
		(layer "F.Cu")
		(at 173.6217 -128.9558 180)
		(property "Reference" "R4B14"
			(at 0 0 180)
			(layer "F.SilkS")
			(hide yes)
			(effects
				(font
					(size 1.27 1.27)
				)
			)
		)
		(property "Value" ""
			(at 0 0 180)
			(layer "F.Fab")
			(effects
				(font
					(size 1.27 1.27)
				)
			)
		)
		(duplicate_pad_numbers_are_jumpers no)
		(fp_rect
			(start -0.2794 0.9906)
			(end 0.2794 -0.1016)
			(stroke
				(width 0)
				(type default)
			)
			(fill no)
			(layer "F.CrtYd")
		)
		(fp_line
			(start 0.2794 0.9906)
			(end 0.2794 -0.1016)
			(stroke
				(width 0.1)
				(type default)
			)
			(layer "F.Fab")
		)
		(fp_line
			(start 0.2794 -0.1016)
			(end -0.2794 -0.1016)
			(stroke
				(width 0.1)
				(type default)
			)
			(layer "F.Fab")
		)
		(fp_line
			(start -0.2794 0.9906)
			(end 0.2794 0.9906)
			(stroke
				(width 0.1)
				(type default)
			)
			(layer "F.Fab")
		)
		(fp_line
			(start -0.2794 -0.1016)
			(end -0.2794 0.9906)
			(stroke
				(width 0.1)
				(type default)
			)
			(layer "F.Fab")
		)
		(pad "1" smd rect
			(at 0 0 180)
			(size 0.508 0.508)
			(layers "F.Cu" "F.Mask" "F.Paste")
			(net "GND")
		)
		(pad "2" smd rect
			(at 0 0.889 180)
			(size 0.508 0.508)
			(layers "F.Cu" "F.Mask" "F.Paste")
			(net "AGND_PVPP_KLM")
		)
		(zone
			(layer "F.Cu")
			(hatch none 0.5)
			(connect_pads
				(clearance 0)
			)
			(min_thickness 0.25)
			(keepout
				(tracks allowed)
				(vias not_allowed)
				(pads allowed)
				(copperpour not_allowed)
				(footprints allowed)
			)
			(placement
				(enabled no)
				(sheetname "")
			)
			(fill
				(thermal_gap 0.5)
				(thermal_bridge_width 0.5)
				(island_removal_mode 0)
			)
			(polygon
				(pts
					(xy 173.8757 -129.5908) (xy 173.3677 -129.5908) (xy 173.3677 -129.2098) (xy 173.8757 -129.2098)
				)
			)
		)
		(zone
			(layer "F.Cu")
			(hatch none 0.5)
			(connect_pads
				(clearance 0)
			)
			(min_thickness 0.25)
			(keepout
				(tracks not_allowed)
				(vias allowed)
				(pads allowed)
				(copperpour not_allowed)
				(footprints allowed)
			)
			(placement
				(enabled no)
				(sheetname "")
			)
			(fill
				(thermal_gap 0.5)
				(thermal_bridge_width 0.5)
				(island_removal_mode 0)
			)
			(polygon
				(pts
					(xy 173.8757 -129.5908) (xy 173.3677 -129.5908) (xy 173.3677 -129.2098) (xy 173.8757 -129.2098)
				)
			)
		)
	)
	(footprint ""
		(layer "F.Cu")
		(at 376.682 -87.3125 180)
		(property "Reference" "R2T1"
			(at -0.8382 -0.67818 180)
			(unlocked yes)
			(layer "F.SilkS")
			(effects
				(font
					(size 0.4064 0.254)
					(thickness 0.1524)
				)
				(justify left)
			)
		)
		(property "Value" ""
			(at 0 0 180)
			(layer "F.Fab")
			(effects
				(font
					(size 1.27 1.27)
				)
			)
		)
		(duplicate_pad_numbers_are_jumpers no)
		(fp_poly
			(pts
				(xy -0.2794 -0.1016) (xy 0.2794 -0.1016) (xy 0.2794 0.9906) (xy -0.2794 0.9906)
			)
			(stroke
				(width 0)
				(type default)
			)
			(fill no)
			(layer "F.CrtYd")
		)
		(fp_line
			(start 0.2794 0.9906)
			(end 0.2794 -0.1016)
			(stroke
				(width 0.1)
				(type default)
			)
			(layer "F.Fab")
		)
		(fp_line
			(start 0.2794 -0.1016)
			(end -0.2794 -0.1016)
			(stroke
				(width 0.1)
				(type default)
			)
			(layer "F.Fab")
		)
		(fp_line
			(start -0.2794 0.9906)
			(end 0.2794 0.9906)
			(stroke
				(width 0.1)
				(type default)
			)
			(layer "F.Fab")
		)
		(fp_line
			(start -0.2794 -0.1016)
			(end -0.2794 0.9906)
			(stroke
				(width 0.1)
				(type default)
			)
			(layer "F.Fab")
		)
		(pad "1" smd rect
			(at 0 0 180)
			(size 0.508 0.508)
			(layers "F.Cu" "F.Mask" "F.Paste")
			(net "SPI_PCH_IO3")
		)
		(pad "2" smd rect
			(at 0 0.889 180)
			(size 0.508 0.508)
			(layers "F.Cu" "F.Mask" "F.Paste")
			(net "GND")
		)
		(zone
			(layer "F.Cu")
			(hatch none 0.5)
			(connect_pads
				(clearance 0)
			)
			(min_thickness 0.25)
			(keepout
				(tracks not_allowed)
				(vias allowed)
				(pads allowed)
				(copperpour not_allowed)
				(footprints allowed)
			)
			(placement
				(enabled no)
				(sheetname "")
			)
			(fill
				(thermal_gap 0.5)
				(thermal_bridge_width 0.5)
				(island_removal_mode 0)
			)
			(polygon
				(pts
					(xy 376.936 -87.9475) (xy 376.428 -87.9475) (xy 376.428 -87.5665) (xy 376.936 -87.5665)
				)
			)
		)
		(zone
			(layer "F.Cu")
			(hatch none 0.5)
			(connect_pads
				(clearance 0)
			)
			(min_thickness 0.25)
			(keepout
				(tracks allowed)
				(vias not_allowed)
				(pads allowed)
				(copperpour not_allowed)
				(footprints allowed)
			)
			(placement
				(enabled no)
				(sheetname "")
			)
			(fill
				(thermal_gap 0.5)
				(thermal_bridge_width 0.5)
				(island_removal_mode 0)
			)
			(polygon
				(pts
					(xy 376.936 -87.5665) (xy 376.428 -87.5665) (xy 376.428 -87.9475) (xy 376.936 -87.9475)
				)
			)
		)
	)
	(footprint ""
		(layer "F.Cu")
		(at 204.649832 -93.36024 -90)
		(property "Reference" "CT59"
			(at -0.8382 -0.67818 270)
			(unlocked yes)
			(layer "F.SilkS")
			(effects
				(font
					(size 0.4064 0.254)
					(thickness 0.1524)
				)
				(justify left)
			)
		)
		(property "Value" ""
			(at 0 0 270)
			(layer "F.Fab")
			(effects
				(font
					(size 1.27 1.27)
				)
			)
		)
		(duplicate_pad_numbers_are_jumpers no)
		(fp_poly
			(pts
				(xy 0.3048 -0.1016) (xy 0.3048 0.9906) (xy -0.3048 0.9906) (xy -0.3048 -0.1016)
			)
			(stroke
				(width 0)
				(type default)
			)
			(fill no)
			(layer "F.CrtYd")
		)
		(fp_line
			(start -0.3048 0.9906)
			(end 0.3048 0.9906)
			(stroke
				(width 0.1)
				(type default)
			)
			(layer "F.Fab")
		)
		(fp_line
			(start 0.3048 0.9906)
			(end 0.3048 -0.1016)
			(stroke
				(width 0.1)
				(type default)
			)
			(layer "F.Fab")
		)
		(fp_line
			(start -0.3048 -0.1016)
			(end -0.3048 0.9906)
			(stroke
				(width 0.1)
				(type default)
			)
			(layer "F.Fab")
		)
		(fp_line
			(start 0.3048 -0.1016)
			(end -0.3048 -0.1016)
			(stroke
				(width 0.1)
				(type default)
			)
			(layer "F.Fab")
		)
		(pad "1" smd rect
			(at 0 0 270)
			(size 0.508 0.508)
			(layers "F.Cu" "F.Mask" "F.Paste")
			(net "VR_PVSA_CPU0_PHASE_SW")
		)
		(pad "2" smd rect
			(at 0 0.889 270)
			(size 0.508 0.508)
			(layers "F.Cu" "F.Mask" "F.Paste")
			(net "VR_PVSA_CPU0_PHASE_SW_RC")
		)
		(zone
			(layer "F.Cu")
			(hatch none 0.5)
			(connect_pads
				(clearance 0)
			)
			(min_thickness 0.25)
			(keepout
				(tracks not_allowed)
				(vias allowed)
				(pads allowed)
				(copperpour not_allowed)
				(footprints allowed)
			)
			(placement
				(enabled no)
				(sheetname "")
			)
			(fill
				(thermal_gap 0.5)
				(thermal_bridge_width 0.5)
				(island_removal_mode 0)
			)
			(polygon
				(pts
					(xy 204.014832 -93.61424) (xy 204.014832 -93.10624) (xy 204.395832 -93.10624) (xy 204.395832 -93.61424)
				)
			)
		)
		(zone
			(layer "F.Cu")
			(hatch none 0.5)
			(connect_pads
				(clearance 0)
			)
			(min_thickness 0.25)
			(keepout
				(tracks allowed)
				(vias not_allowed)
				(pads allowed)
				(copperpour not_allowed)
				(footprints allowed)
			)
			(placement
				(enabled no)
				(sheetname "")
			)
			(fill
				(thermal_gap 0.5)
				(thermal_bridge_width 0.5)
				(island_removal_mode 0)
			)
			(polygon
				(pts
					(xy 204.395832 -93.61424) (xy 204.395832 -93.10624) (xy 204.014832 -93.10624) (xy 204.014832 -93.61424)
				)
			)
		)
	)
)
